# S9S_MB_2U (Grand Teton) — schematic netlist excerpt (pin names and nets, part order shuffled) for the footprints in the layout excerpt that follows; sources: Cadence DE-HDL packaged netlist, KiCad conversion of 03242023_DA0F0TMBIJ0_F0T_Motherboard_J_brd_V01_OCP.brd

C1322  Q_CAP  0.1UF 25V 10% X7R  pkg 0402  page 239 : A = P3V3_AUX ; B = GND
R2921  Q_RES  10K 1% EMPTY  pkg 0402LF  page 227 : A = P3V3_AUX ; B = RST_SMB_SWITCH_N

(kicad_pcb
	(version 20260206)
	(generator "pcbnew")
	(generator_version "10.0")
	(general
		(thickness 1.6)
		(legacy_teardrops no)
	)
	(paper "A4")
	(title_block
		(title "03242023_DA0F0TMBIJ0_F0T_Motherboard_J_brd_V01_OCP.brd")
		(comment 1 "Grand Teton / footprints 1858-1859 of 6105")
	)
	(layers
		(0 "F.Cu" signal "TOP")
		(4 "In1.Cu" signal "GND")
		(6 "In2.Cu" signal "IN1")
		(8 "In3.Cu" signal "GND1")
		(10 "In4.Cu" signal "IN2")
		(12 "In5.Cu" signal "GND2")
		(14 "In6.Cu" signal "IN3")
		(16 "In7.Cu" signal "GND3")
		(18 "In8.Cu" signal "VCC")
		(20 "In9.Cu" signal "VCC1")
		(22 "In10.Cu" signal "GND4")
		(24 "In11.Cu" signal "IN4")
		(26 "In12.Cu" signal "GND5")
		(28 "In13.Cu" signal "IN5")
		(30 "In14.Cu" signal "GND6")
		(32 "In15.Cu" signal "IN6")
		(34 "In16.Cu" signal "GND7")
		(2 "B.Cu" signal "BOTTOM")
		(9 "F.Adhes" user "F.Adhesive")
		(11 "B.Adhes" user "B.Adhesive")
		(13 "F.Paste" user "Package Geometry/Pastemask Top")
		(15 "B.Paste" user "Package Geometry/Pastemask Bottom")
		(5 "F.SilkS" user "Ref Des/Silkscreen Top")
		(7 "B.SilkS" user "Ref Des/Silkscreen Bottom")
		(1 "F.Mask" user "Board Geometry/Soldermask Top")
		(3 "B.Mask" user "Board Geometry/Soldermask Bottom")
		(17 "Dwgs.User" user "User.Drawings")
		(19 "Cmts.User" user "User.Comments")
		(21 "Eco1.User" user "User.Eco1")
		(23 "Eco2.User" user "User.Eco2")
		(25 "Edge.Cuts" user "Board Geometry/Outline")
		(27 "Margin" user)
		(31 "F.CrtYd" user "Package Geometry/Place Bound Top")
		(29 "B.CrtYd" user "Package Geometry/Place Bound Bottom")
		(35 "F.Fab" user "Ref Des/Assembly Top")
		(33 "B.Fab" user "Ref Des/Assembly Bottom")
	)
	(footprint ""
		(layer "F.Cu")
		(at 127.288544 -74.853292 -90)
		(property "Reference" "C1322"
			(at 0 0 270)
			(layer "F.SilkS")
			(hide yes)
			(effects
				(font
					(size 1.27 1.27)
				)
			)
		)
		(property "Value" ""
			(at 0 0 270)
			(layer "F.Fab")
			(effects
				(font
					(size 1.27 1.27)
				)
			)
		)
		(duplicate_pad_numbers_are_jumpers no)
		(fp_line
			(start -0.7874 0.4064)
			(end -0.7874 -0.4064)
			(stroke
				(width 0.1524)
				(type default)
			)
			(layer "F.SilkS")
		)
		(fp_line
			(start 0.7874 0.4064)
			(end -0.7874 0.4064)
			(stroke
				(width 0.1524)
				(type default)
			)
			(layer "F.SilkS")
		)
		(fp_line
			(start -0.7874 -0.4064)
			(end 0.7874 -0.4064)
			(stroke
				(width 0.1524)
				(type default)
			)
			(layer "F.SilkS")
		)
		(fp_line
			(start 0.7874 -0.4064)
			(end 0.7874 0.4064)
			(stroke
				(width 0.1524)
				(type default)
			)
			(layer "F.SilkS")
		)
		(fp_line
			(start -0.67945 0.3048)
			(end -0.67945 -0.305054)
			(stroke
				(width 0.1)
				(type default)
			)
			(layer "F.Fab")
		)
		(fp_line
			(start -0.12065 0.3048)
			(end -0.67945 0.3048)
			(stroke
				(width 0.1)
				(type default)
			)
			(layer "F.Fab")
		)
		(fp_line
			(start 0.120396 0.3048)
			(end 0.120396 0.2794)
			(stroke
				(width 0.1)
				(type default)
			)
			(layer "F.Fab")
		)
		(fp_line
			(start 0.67945 0.3048)
			(end 0.120396 0.3048)
			(stroke
				(width 0.1)
				(type default)
			)
			(layer "F.Fab")
		)
		(fp_line
			(start -0.12065 0.2794)
			(end -0.12065 0.3048)
			(stroke
				(width 0.1)
				(type default)
			)
			(layer "F.Fab")
		)
		(fp_line
			(start 0.120396 0.2794)
			(end -0.12065 0.2794)
			(stroke
				(width 0.1)
				(type default)
			)
			(layer "F.Fab")
		)
		(fp_line
			(start -0.12065 -0.2794)
			(end 0.12065 -0.2794)
			(stroke
				(width 0.1)
				(type default)
			)
			(layer "F.Fab")
		)
		(fp_line
			(start 0.12065 -0.2794)
			(end 0.12065 -0.3048)
			(stroke
				(width 0.1)
				(type default)
			)
			(layer "F.Fab")
		)
		(fp_line
			(start 0.12065 -0.3048)
			(end 0.67945 -0.3048)
			(stroke
				(width 0.1)
				(type default)
			)
			(layer "F.Fab")
		)
		(fp_line
			(start 0.67945 -0.3048)
			(end 0.67945 0.3048)
			(stroke
				(width 0.1)
				(type default)
			)
			(layer "F.Fab")
		)
		(fp_line
			(start -0.67945 -0.305054)
			(end -0.12065 -0.305054)
			(stroke
				(width 0.1)
				(type default)
			)
			(layer "F.Fab")
		)
		(fp_line
			(start -0.12065 -0.305054)
			(end -0.12065 -0.2794)
			(stroke
				(width 0.1)
				(type default)
			)
			(layer "F.Fab")
		)
		(pad "1" smd circle
			(at -0.40005 0 270)
			(size 0 0)
			(layers "F.Cu" "F.Mask" "F.Paste")
			(net "P3V3_AUX")
		)
		(pad "2" smd circle
			(at 0.40005 0 270)
			(size 0 0)
			(layers "F.Cu" "F.Mask" "F.Paste")
			(net "GND")
		)
	)
	(footprint ""
		(layer "F.Cu")
		(at 15.197582 -408.516836 90)
		(property "Reference" "R2921"
			(at 0 0 90)
			(layer "F.SilkS")
			(hide yes)
			(effects
				(font
					(size 1.27 1.27)
				)
			)
		)
		(property "Value" ""
			(at 0 0 90)
			(layer "F.Fab")
			(effects
				(font
					(size 1.27 1.27)
				)
			)
		)
		(duplicate_pad_numbers_are_jumpers no)
		(fp_line
			(start 0.7874 -0.4064)
			(end 0.7874 0.4064)
			(stroke
				(width 0.1524)
				(type default)
			)
			(layer "F.SilkS")
		)
		(fp_line
			(start -0.7874 -0.4064)
			(end 0.7874 -0.4064)
			(stroke
				(width 0.1524)
				(type default)
			)
			(layer "F.SilkS")
		)
		(fp_line
			(start 0.7874 0.4064)
			(end -0.7874 0.4064)
			(stroke
				(width 0.1524)
				(type default)
			)
			(layer "F.SilkS")
		)
		(fp_line
			(start -0.7874 0.4064)
			(end -0.7874 -0.4064)
			(stroke
				(width 0.1524)
				(type default)
			)
			(layer "F.SilkS")
		)
		(fp_line
			(start -0.12065 -0.305054)
			(end -0.12065 -0.2794)
			(stroke
				(width 0.1)
				(type default)
			)
			(layer "F.Fab")
		)
		(fp_line
			(start -0.67945 -0.305054)
			(end -0.12065 -0.305054)
			(stroke
				(width 0.1)
				(type default)
			)
			(layer "F.Fab")
		)
		(fp_line
			(start 0.67945 -0.3048)
			(end 0.67945 0.3048)
			(stroke
				(width 0.1)
				(type default)
			)
			(layer "F.Fab")
		)
		(fp_line
			(start 0.12065 -0.3048)
			(end 0.67945 -0.3048)
			(stroke
				(width 0.1)
				(type default)
			)
			(layer "F.Fab")
		)
		(fp_line
			(start 0.12065 -0.2794)
			(end 0.12065 -0.3048)
			(stroke
				(width 0.1)
				(type default)
			)
			(layer "F.Fab")
		)
		(fp_line
			(start -0.12065 -0.2794)
			(end 0.12065 -0.2794)
			(stroke
				(width 0.1)
				(type default)
			)
			(layer "F.Fab")
		)
		(fp_line
			(start 0.120396 0.2794)
			(end -0.12065 0.2794)
			(stroke
				(width 0.1)
				(type default)
			)
			(layer "F.Fab")
		)
		(fp_line
			(start -0.12065 0.2794)
			(end -0.12065 0.3048)
			(stroke
				(width 0.1)
				(type default)
			)
			(layer "F.Fab")
		)
		(fp_line
			(start 0.67945 0.3048)
			(end 0.120396 0.3048)
			(stroke
				(width 0.1)
				(type default)
			)
			(layer "F.Fab")
		)
		(fp_line
			(start 0.120396 0.3048)
			(end 0.120396 0.2794)
			(stroke
				(width 0.1)
				(type default)
			)
			(layer "F.Fab")
		)
		(fp_line
			(start -0.12065 0.3048)
			(end -0.67945 0.3048)
			(stroke
				(width 0.1)
				(type default)
			)
			(layer "F.Fab")
		)
		(fp_line
			(start -0.67945 0.3048)
			(end -0.67945 -0.305054)
			(stroke
				(width 0.1)
				(type default)
			)
			(layer "F.Fab")
		)
		(pad "1" smd circle
			(at -0.40005 0 90)
			(size 0 0)
			(layers "F.Cu" "F.Mask" "F.Paste")
			(net "P3V3_AUX")
		)
		(pad "2" smd circle
			(at 0.40005 0 90)
			(size 0 0)
			(layers "F.Cu" "F.Mask" "F.Paste")
			(net "RST_SMB_SWITCH_N")
		)
	)
)
